(kicad_pcb
	(version 20241229)
	(generator "pcbnew")
	(generator_version "9.0")
	(general
		(thickness 1.6)
		(legacy_teardrops no)
	)
	(paper "A4")
	(title_block
		(title "GMSL Deserializer")
		(date "2025-10-09")
		(rev "1.0.4")
		(company "Antmicro Ltd")
		(comment 1 "www.antmicro.com")
		(comment 9 "footprints 206-211 of 235")
	)
	(layers
		(0 "F.Cu" signal)
		(4 "In1.Cu" power)
		(6 "In2.Cu" power)
		(2 "B.Cu" signal)
		(9 "F.Adhes" user "F.Adhesive")
		(11 "B.Adhes" user "B.Adhesive")
		(13 "F.Paste" user)
		(15 "B.Paste" user)
		(5 "F.SilkS" user "F.Silkscreen")
		(7 "B.SilkS" user "B.Silkscreen")
		(1 "F.Mask" user)
		(3 "B.Mask" user)
		(17 "Dwgs.User" user "User.Drawings")
		(19 "Cmts.User" user "User.Comments")
		(21 "Eco1.User" user "User.Eco1")
		(23 "Eco2.User" user "User.Eco2")
		(25 "Edge.Cuts" user)
		(27 "Margin" user)
		(31 "F.CrtYd" user "F.Courtyard")
		(29 "B.CrtYd" user "B.Courtyard")
		(35 "F.Fab" user)
		(33 "B.Fab" user)
	)
	(footprint "antmicro-footprints:SOT-523"
		(layer "B.Cu")
		(at 162.45 96.2 180)
		(property "Reference" "Q6"
			(at -1.25 1.3 0)
			(layer "B.SilkS")
			(effects
				(font
					(size 0.7 0.7)
					(thickness 0.15)
				)
				(justify left bottom mirror)
			)
		)
		(property "Value" "DMG1012T-7"
			(at 0.1 -1.824 0)
			(layer "B.Fab")
			(effects
				(font
					(size 0.7 0.7)
					(thickness 0.15)
				)
				(justify left bottom mirror)
			)
		)
		(property "Datasheet" "https://www.diodes.com/assets/Datasheets/ds31783.pdf"
			(at 0 0 180)
			(layer "F.Fab")
			(hide yes)
			(effects
				(font
					(size 1.27 1.27)
					(thickness 0.15)
				)
			)
		)
		(property "Description" "Power MOSFET, N Channel, 20 V, 630 mA, 0.3 ohm, SOT-523, Surface Mount"
			(at 0 0 180)
			(layer "F.Fab")
			(hide yes)
			(effects
				(font
					(size 1.27 1.27)
					(thickness 0.15)
				)
			)
		)
		(property "Author" "Antmicro"
			(at 324.9 192.4 0)
			(layer "B.Fab")
			(hide yes)
			(effects
				(font
					(size 1 1)
					(thickness 0.15)
				)
				(justify mirror)
			)
		)
		(property "License" "Apache-2.0"
			(at 324.9 192.4 0)
			(layer "B.Fab")
			(hide yes)
			(effects
				(font
					(size 1 1)
					(thickness 0.15)
				)
				(justify mirror)
			)
		)
		(property "MPN" "DMG1012T-7"
			(at 324.9 192.4 0)
			(layer "B.Fab")
			(hide yes)
			(effects
				(font
					(size 1 1)
					(thickness 0.15)
				)
				(justify mirror)
			)
		)
		(property "Manufacturer" "Diodes Incorporated"
			(at 324.9 192.4 0)
			(layer "B.Fab")
			(hide yes)
			(effects
				(font
					(size 1 1)
					(thickness 0.15)
				)
				(justify mirror)
			)
		)
		(property "Public" ""
			(at 324.9 192.4 0)
			(layer "B.Fab")
			(hide yes)
			(effects
				(font
					(size 1 1)
					(thickness 0.15)
				)
				(justify mirror)
			)
		)
		(sheetname "/Connectors/")
		(sheetfile "connectors.kicad_sch")
		(attr smd)
		(fp_line
			(start -0.277 0.75)
			(end -0.277 0.551)
			(stroke
				(width 0.15)
				(type solid)
			)
			(layer "B.SilkS")
		)
		(fp_line
			(start -0.277 0.551)
			(end -0.725 0.551)
			(stroke
				(width 0.15)
				(type solid)
			)
			(layer "B.SilkS")
		)
		(fp_line
			(start -0.725 0.551)
			(end -0.927 0.351)
			(stroke
				(width 0.15)
				(type solid)
			)
			(layer "B.SilkS")
		)
		(fp_line
			(start -0.927 0.351)
			(end -0.927 0.051)
			(stroke
				(width 0.15)
				(type solid)
			)
			(layer "B.SilkS")
		)
		(fp_circle
			(center -0.9652 -0.9652)
			(end -0.9152 -0.9652)
			(stroke
				(width 0.15)
				(type solid)
			)
			(fill yes)
			(layer "B.SilkS")
		)
		(fp_line
			(start 1.1 1.16)
			(end -1.12 1.16)
			(stroke
				(width 0.05)
				(type solid)
			)
			(layer "B.CrtYd")
		)
		(fp_line
			(start 1.1 -1.15)
			(end 1.1 1.16)
			(stroke
				(width 0.05)
				(type solid)
			)
			(layer "B.CrtYd")
		)
		(fp_line
			(start 1.1 -1.15)
			(end -1.12 -1.15)
			(stroke
				(width 0.05)
				(type solid)
			)
			(layer "B.CrtYd")
		)
		(fp_line
			(start -1.12 -1.15)
			(end -1.12 1.16)
			(stroke
				(width 0.05)
				(type solid)
			)
			(layer "B.CrtYd")
		)
		(fp_line
			(start 0.8 -0.424)
			(end 0.8 0.425)
			(stroke
				(width 0.15)
				(type solid)
			)
			(layer "B.Fab")
		)
		(fp_line
			(start -0.652 0.425)
			(end 0.8 0.425)
			(stroke
				(width 0.15)
				(type solid)
			)
			(layer "B.Fab")
		)
		(fp_line
			(start -0.802 0.276)
			(end -0.652 0.425)
			(stroke
				(width 0.15)
				(type solid)
			)
			(layer "B.Fab")
		)
		(fp_line
			(start -0.802 -0.424)
			(end 0.8 -0.424)
			(stroke
				(width 0.15)
				(type solid)
			)
			(layer "B.Fab")
		)
		(fp_line
			(start -0.802 -0.424)
			(end -0.802 0.276)
			(stroke
				(width 0.15)
				(type solid)
			)
			(layer "B.Fab")
		)
		(fp_circle
			(center -0.9652 -0.9652)
			(end -0.9144 -0.9652)
			(stroke
				(width 0.15)
				(type solid)
			)
			(fill no)
			(layer "B.Fab")
		)
		(pad "1" smd rect
			(at -0.5 -0.65 180)
			(size 0.4 0.51)
			(layers "B.Cu" "B.Mask" "B.Paste")
			(net 84 "/Connectors/MFP4")
			(pinfunction "G")
			(pintype "input")
		)
		(pad "2" smd rect
			(at 0.498 -0.65 180)
			(size 0.4 0.51)
			(layers "B.Cu" "B.Mask" "B.Paste")
			(net 1 "GND")
			(pinfunction "S")
			(pintype "passive")
		)
		(pad "3" smd rect
			(at 0 0.652 180)
			(size 0.4 0.51)
			(layers "B.Cu" "B.Mask" "B.Paste")
			(net 111 "Net-(D14-C)")
			(pinfunction "D")
			(pintype "passive")
		)
	)
	(footprint "antmicro-footprints:R_0402_1005Metric"
		(layer "B.Cu")
		(at 158.500124 96.375897 -90)
		(descr "Resistor SMD 0402")
		(tags "resistor SMD 0402")
		(property "Reference" "R82"
			(at -2.935369 -0.483209 90)
			(layer "B.SilkS")
			(effects
				(font
					(size 0.7 0.7)
					(thickness 0.15)
				)
				(justify left bottom mirror)
			)
		)
		(property "Value" "R_470R_0402"
			(at -1.011843 -1.772046 90)
			(layer "B.Fab")
			(effects
				(font
					(size 0.7 0.7)
					(thickness 0.15)
				)
				(justify left bottom mirror)
			)
		)
		(property "Datasheet" "https://www.bourns.com/docs/product-datasheets/cr.pdf"
			(at 0 0 90)
			(layer "F.Fab")
			(hide yes)
			(effects
				(font
					(size 1.27 1.27)
					(thickness 0.15)
				)
			)
		)
		(property "Description" "SMD Chip Resistor, 470 ohm, ± 1%, 62.5 mW, 0402 [1005 Metric], Thick Film, General Purpose"
			(at 0 0 90)
			(layer "F.Fab")
			(hide yes)
			(effects
				(font
					(size 1.27 1.27)
					(thickness 0.15)
				)
			)
		)
		(property "Author" "Antmicro"
			(at -21.176172 140.355021 135)
			(layer "B.Fab")
			(hide yes)
			(effects
				(font
					(size 1 1)
					(thickness 0.15)
				)
				(justify mirror)
			)
		)
		(property "License" "Apache-2.0"
			(at -21.176172 140.355021 135)
			(layer "B.Fab")
			(hide yes)
			(effects
				(font
					(size 1 1)
					(thickness 0.15)
				)
				(justify mirror)
			)
		)
		(property "MPN" "CR0402-FX-4700GLF"
			(at -21.176172 140.355021 135)
			(layer "B.Fab")
			(hide yes)
			(effects
				(font
					(size 1 1)
					(thickness 0.15)
				)
				(justify mirror)
			)
		)
		(property "Manufacturer" "Bourns"
			(at -21.176172 140.355021 135)
			(layer "B.Fab")
			(hide yes)
			(effects
				(font
					(size 1 1)
					(thickness 0.15)
				)
				(justify mirror)
			)
		)
		(property "Tolerance" "1%"
			(at -21.176172 140.355021 135)
			(layer "B.Fab")
			(hide yes)
			(effects
				(font
					(size 1 1)
					(thickness 0.15)
				)
				(justify mirror)
			)
		)
		(property "Val" "470R"
			(at -21.176172 140.355021 135)
			(layer "B.Fab")
			(hide yes)
			(effects
				(font
					(size 1 1)
					(thickness 0.15)
				)
				(justify mirror)
			)
		)
		(sheetname "/Connectors/")
		(sheetfile "connectors.kicad_sch")
		(attr smd)
		(fp_poly
			(pts
				(xy -0.925 0.47) (xy 0.925 0.47) (xy 0.925 -0.47) (xy -0.925 -0.47)
			)
			(stroke
				(width 0.05)
				(type default)
			)
			(fill no)
			(layer "B.CrtYd")
		)
		(fp_poly
			(pts
				(xy -0.5 0.25) (xy 0.5 0.25) (xy 0.5 -0.25) (xy -0.5 -0.25)
			)
			(stroke
				(width 0.15)
				(type solid)
			)
			(fill no)
			(layer "B.Fab")
		)
		(pad "1" smd roundrect
			(at -0.48 0 270)
			(size 0.59 0.64)
			(layers "B.Cu" "B.Mask" "B.Paste")
			(roundrect_rratio 0.25)
			(net 110 "Net-(D14-A)")
			(pintype "passive")
		)
		(pad "2" smd roundrect
			(at 0.48 0 270)
			(size 0.59 0.64)
			(layers "B.Cu" "B.Mask" "B.Paste")
			(roundrect_rratio 0.25)
			(net 5 "+5V")
			(pintype "passive")
		)
	)
	(footprint "antmicro-footprints:TP_SMD_0.75mm"
		(layer "B.Cu")
		(at 130.81 84.8 180)
		(property "Reference" "TP27"
			(at 0 0.6 0)
			(layer "B.SilkS")
			(hide yes)
			(effects
				(font
					(size 0.7 0.7)
					(thickness 0.15)
				)
				(justify left bottom mirror)
			)
		)
		(property "Value" "TP_0.75mm_SMD"
			(at 0 -1.2 0)
			(layer "B.Fab")
			(effects
				(font
					(size 0.7 0.7)
					(thickness 0.15)
				)
				(justify left bottom mirror)
			)
		)
		(property "Description" "SMT test point"
			(at 0 0 0)
			(layer "B.Fab")
			(hide yes)
			(effects
				(font
					(size 1.27 1.27)
					(thickness 0.15)
				)
				(justify mirror)
			)
		)
		(property "MPN" ""
			(at 0 0 0)
			(unlocked yes)
			(layer "B.Fab")
			(hide yes)
			(effects
				(font
					(size 1 1)
					(thickness 0.15)
				)
				(justify mirror)
			)
		)
		(property "Manufacturer" ""
			(at 0 0 0)
			(unlocked yes)
			(layer "B.Fab")
			(hide yes)
			(effects
				(font
					(size 1 1)
					(thickness 0.15)
				)
				(justify mirror)
			)
		)
		(property "Author" "Antmicro"
			(at 0 0 0)
			(unlocked yes)
			(layer "B.Fab")
			(hide yes)
			(effects
				(font
					(size 1 1)
					(thickness 0.15)
				)
				(justify mirror)
			)
		)
		(property "License" "Apache-2.0"
			(at 0 0 0)
			(unlocked yes)
			(layer "B.Fab")
			(hide yes)
			(effects
				(font
					(size 1 1)
					(thickness 0.15)
				)
				(justify mirror)
			)
		)
		(sheetname "/Power/")
		(sheetfile "power.kicad_sch")
		(attr exclude_from_pos_files)
		(fp_circle
			(center 0 0)
			(end 0.475 0)
			(stroke
				(width 0.05)
				(type default)
			)
			(fill no)
			(layer "B.CrtYd")
		)
		(fp_text user "${REFERENCE}"
			(at -0.4 -2.7 0)
			(layer "B.Fab")
			(effects
				(font
					(size 0.7 0.7)
					(thickness 0.15)
				)
				(justify left bottom mirror)
			)
		)
		(fp_text user "Author: Antmicro"
			(at -0.4 -3.901 0)
			(layer "B.Fab")
			(effects
				(font
					(size 0.7 0.7)
					(thickness 0.15)
				)
				(justify left bottom mirror)
			)
		)
		(fp_text user "License: Apache-2.0"
			(at -0.4 -5.101 0)
			(layer "B.Fab")
			(effects
				(font
					(size 0.7 0.7)
					(thickness 0.15)
				)
				(justify left bottom mirror)
			)
		)
		(pad "1" smd circle
			(at 0 0 180)
			(size 0.75 0.75)
			(layers "B.Cu" "B.Mask")
			(net 73 "+1V2")
			(pinfunction "1")
			(pintype "passive")
		)
	)
	(footprint "antmicro-footprints:TP_SMD_0.75mm"
		(layer "B.Cu")
		(at 149.35 97.9 180)
		(property "Reference" "TP20"
			(at 0 0.6 0)
			(layer "B.SilkS")
			(hide yes)
			(effects
				(font
					(size 0.7 0.7)
					(thickness 0.15)
				)
				(justify left bottom mirror)
			)
		)
		(property "Value" "TP_0.75mm_SMD"
			(at 0 -1.2 0)
			(layer "B.Fab")
			(effects
				(font
					(size 0.7 0.7)
					(thickness 0.15)
				)
				(justify left bottom mirror)
			)
		)
		(property "Description" "SMT test point"
			(at 0 0 0)
			(layer "B.Fab")
			(hide yes)
			(effects
				(font
					(size 1.27 1.27)
					(thickness 0.15)
				)
				(justify mirror)
			)
		)
		(property "MPN" ""
			(at 0 0 0)
			(unlocked yes)
			(layer "B.Fab")
			(hide yes)
			(effects
				(font
					(size 1 1)
					(thickness 0.15)
				)
				(justify mirror)
			)
		)
		(property "Manufacturer" ""
			(at 0 0 0)
			(unlocked yes)
			(layer "B.Fab")
			(hide yes)
			(effects
				(font
					(size 1 1)
					(thickness 0.15)
				)
				(justify mirror)
			)
		)
		(property "Author" "Antmicro"
			(at 0 0 0)
			(unlocked yes)
			(layer "B.Fab")
			(hide yes)
			(effects
				(font
					(size 1 1)
					(thickness 0.15)
				)
				(justify mirror)
			)
		)
		(property "License" "Apache-2.0"
			(at 0 0 0)
			(unlocked yes)
			(layer "B.Fab")
			(hide yes)
			(effects
				(font
					(size 1 1)
					(thickness 0.15)
				)
				(justify mirror)
			)
		)
		(sheetname "/Power/")
		(sheetfile "power.kicad_sch")
		(attr exclude_from_pos_files)
		(fp_circle
			(center 0 0)
			(end 0.475 0)
			(stroke
				(width 0.05)
				(type default)
			)
			(fill no)
			(layer "B.CrtYd")
		)
		(fp_text user "Author: Antmicro"
			(at -0.4 -3.901 0)
			(layer "B.Fab")
			(effects
				(font
					(size 0.7 0.7)
					(thickness 0.15)
				)
				(justify left bottom mirror)
			)
		)
		(fp_text user "${REFERENCE}"
			(at -0.4 -2.7 0)
			(layer "B.Fab")
			(effects
				(font
					(size 0.7 0.7)
					(thickness 0.15)
				)
				(justify left bottom mirror)
			)
		)
		(fp_text user "License: Apache-2.0"
			(at -0.4 -5.101 0)
			(layer "B.Fab")
			(effects
				(font
					(size 0.7 0.7)
					(thickness 0.15)
				)
				(justify left bottom mirror)
			)
		)
		(pad "1" smd circle
			(at 0 0 180)
			(size 0.75 0.75)
			(layers "B.Cu" "B.Mask")
			(net 4 "+12V")
			(pinfunction "1")
			(pintype "passive")
		)
	)
	(footprint "antmicro-footprints:R_0402_1005Metric"
		(layer "B.Cu")
		(at 147.867621 96.375897 90)
		(descr "Resistor SMD 0402")
		(tags "resistor SMD 0402")
		(property "Reference" "R78"
			(at 5.724873 0.425736 90)
			(layer "B.SilkS")
			(effects
				(font
					(size 0.7 0.7)
					(thickness 0.15)
				)
				(justify right bottom mirror)
			)
		)
		(property "Value" "R_1k65_0402"
			(at -1.011843 -1.772046 90)
			(layer "B.Fab")
			(effects
				(font
					(size 0.7 0.7)
					(thickness 0.15)
				)
				(justify right bottom mirror)
			)
		)
		(property "Datasheet" "https://www.farnell.com/datasheets/3795017.pdf"
			(at 0 0 90)
			(layer "F.Fab")
			(hide yes)
			(effects
				(font
					(size 1.27 1.27)
					(thickness 0.15)
				)
			)
		)
		(property "Description" "SMD Chip Resistor, 1.65 kohm, ± 1%, 63 mW, 0402 [1005 Metric], Thick Film, General Purpose"
			(at 0 0 90)
			(layer "F.Fab")
			(hide yes)
			(effects
				(font
					(size 1.27 1.27)
					(thickness 0.15)
				)
			)
		)
		(property "Author" "Antmicro"
			(at 320.63778 58.566305 135)
			(layer "B.Fab")
			(hide yes)
			(effects
				(font
					(size 1 1)
					(thickness 0.15)
				)
				(justify mirror)
			)
		)
		(property "License" "Apache-2.0"
			(at 320.63778 58.566305 135)
			(layer "B.Fab")
			(hide yes)
			(effects
				(font
					(size 1 1)
					(thickness 0.15)
				)
				(justify mirror)
			)
		)
		(property "MPN" "RC0402FR-071K65L"
			(at 320.63778 58.566305 135)
			(layer "B.Fab")
			(hide yes)
			(effects
				(font
					(size 1 1)
					(thickness 0.15)
				)
				(justify mirror)
			)
		)
		(property "Manufacturer" "YAGEO"
			(at 320.63778 58.566305 135)
			(layer "B.Fab")
			(hide yes)
			(effects
				(font
					(size 1 1)
					(thickness 0.15)
				)
				(justify mirror)
			)
		)
		(property "Public" ""
			(at 320.63778 58.566305 135)
			(layer "B.Fab")
			(hide yes)
			(effects
				(font
					(size 1 1)
					(thickness 0.15)
				)
				(justify mirror)
			)
		)
		(property "Tolerance" "1%"
			(at 320.63778 58.566305 135)
			(layer "B.Fab")
			(hide yes)
			(effects
				(font
					(size 1 1)
					(thickness 0.15)
				)
				(justify mirror)
			)
		)
		(property "Val" "1k65"
			(at 320.63778 58.566305 135)
			(layer "B.Fab")
			(hide yes)
			(effects
				(font
					(size 1 1)
					(thickness 0.15)
				)
				(justify mirror)
			)
		)
		(sheetname "/Power/")
		(sheetfile "power.kicad_sch")
		(attr smd)
		(fp_poly
			(pts
				(xy -0.925 0.47) (xy 0.925 0.47) (xy 0.925 -0.47) (xy -0.925 -0.47)
			)
			(stroke
				(width 0.05)
				(type default)
			)
			(fill no)
			(layer "B.CrtYd")
		)
		(fp_poly
			(pts
				(xy -0.5 0.25) (xy 0.5 0.25) (xy 0.5 -0.25) (xy -0.5 -0.25)
			)
			(stroke
				(width 0.15)
				(type solid)
			)
			(fill no)
			(layer "B.Fab")
		)
		(pad "1" smd roundrect
			(at -0.48 0 90)
			(size 0.59 0.64)
			(layers "B.Cu" "B.Mask" "B.Paste")
			(roundrect_rratio 0.25)
			(net 1 "GND")
			(pintype "passive")
		)
		(pad "2" smd roundrect
			(at 0.48 0 90)
			(size 0.59 0.64)
			(layers "B.Cu" "B.Mask" "B.Paste")
			(roundrect_rratio 0.25)
			(net 142 "Net-(D18-C)")
			(pintype "passive")
		)
	)
	(footprint "antmicro-footprints:SOT-523"
		(layer "B.Cu")
		(at 138.2 89.65)
		(property "Reference" "Q5"
			(at -0.75 2 0)
			(layer "B.SilkS")
			(effects
				(font
					(size 0.7 0.7)
					(thickness 0.15)
				)
				(justify right bottom mirror)
			)
		)
		(property "Value" "DMG1012T-7"
			(at 0.1 -1.824 0)
			(layer "B.Fab")
			(effects
				(font
					(size 0.7 0.7)
					(thickness 0.15)
				)
				(justify right bottom mirror)
			)
		)
		(property "Datasheet" "https://www.diodes.com/assets/Datasheets/ds31783.pdf"
			(at 0 0 0)
			(layer "F.Fab")
			(hide yes)
			(effects
				(font
					(size 1.27 1.27)
					(thickness 0.15)
				)
			)
		)
		(property "Description" "Power MOSFET, N Channel, 20 V, 630 mA, 0.3 ohm, SOT-523, Surface Mount"
			(at 0 0 0)
			(layer "F.Fab")
			(hide yes)
			(effects
				(font
					(size 1.27 1.27)
					(thickness 0.15)
				)
			)
		)
		(property "Author" "Antmicro"
			(at 0 0 0)
			(layer "B.Fab")
			(hide yes)
			(effects
				(font
					(size 1 1)
					(thickness 0.15)
				)
				(justify mirror)
			)
		)
		(property "License" "Apache-2.0"
			(at 0 0 0)
			(layer "B.Fab")
			(hide yes)
			(effects
				(font
					(size 1 1)
					(thickness 0.15)
				)
				(justify mirror)
			)
		)
		(property "MPN" "DMG1012T-7"
			(at 0 0 0)
			(layer "B.Fab")
			(hide yes)
			(effects
				(font
					(size 1 1)
					(thickness 0.15)
				)
				(justify mirror)
			)
		)
		(property "Manufacturer" "Diodes Incorporated"
			(at 0 0 0)
			(layer "B.Fab")
			(hide yes)
			(effects
				(font
					(size 1 1)
					(thickness 0.15)
				)
				(justify mirror)
			)
		)
		(property "Public" ""
			(at 0 0 0)
			(layer "B.Fab")
			(hide yes)
			(effects
				(font
					(size 1 1)
					(thickness 0.15)
				)
				(justify mirror)
			)
		)
		(sheetname "/Power/")
		(sheetfile "power.kicad_sch")
		(attr smd)
		(fp_line
			(start -0.927 0.351)
			(end -0.927 0.051)
			(stroke
				(width 0.15)
				(type solid)
			)
			(layer "B.SilkS")
		)
		(fp_line
			(start -0.725 0.551)
			(end -0.927 0.351)
			(stroke
				(width 0.15)
				(type solid)
			)
			(layer "B.SilkS")
		)
		(fp_line
			(start -0.277 0.551)
			(end -0.725 0.551)
			(stroke
				(width 0.15)
				(type solid)
			)
			(layer "B.SilkS")
		)
		(fp_line
			(start -0.277 0.75)
			(end -0.277 0.551)
			(stroke
				(width 0.15)
				(type solid)
			)
			(layer "B.SilkS")
		)
		(fp_circle
			(center -0.9652 -0.9652)
			(end -0.9152 -0.9652)
			(stroke
				(width 0.15)
				(type solid)
			)
			(fill yes)
			(layer "B.SilkS")
		)
		(fp_line
			(start -1.12 -1.15)
			(end -1.12 1.16)
			(stroke
				(width 0.05)
				(type solid)
			)
			(layer "B.CrtYd")
		)
		(fp_line
			(start 1.1 -1.15)
			(end -1.12 -1.15)
			(stroke
				(width 0.05)
				(type solid)
			)
			(layer "B.CrtYd")
		)
		(fp_line
			(start 1.1 -1.15)
			(end 1.1 1.16)
			(stroke
				(width 0.05)
				(type solid)
			)
			(layer "B.CrtYd")
		)
		(fp_line
			(start 1.1 1.16)
			(end -1.12 1.16)
			(stroke
				(width 0.05)
				(type solid)
			)
			(layer "B.CrtYd")
		)
		(fp_line
			(start -0.802 -0.424)
			(end -0.802 0.276)
			(stroke
				(width 0.15)
				(type solid)
			)
			(layer "B.Fab")
		)
		(fp_line
			(start -0.802 -0.424)
			(end 0.8 -0.424)
			(stroke
				(width 0.15)
				(type solid)
			)
			(layer "B.Fab")
		)
		(fp_line
			(start -0.802 0.276)
			(end -0.652 0.425)
			(stroke
				(width 0.15)
				(type solid)
			)
			(layer "B.Fab")
		)
		(fp_line
			(start -0.652 0.425)
			(end 0.8 0.425)
			(stroke
				(width 0.15)
				(type solid)
			)
			(layer "B.Fab")
		)
		(fp_line
			(start 0.8 -0.424)
			(end 0.8 0.425)
			(stroke
				(width 0.15)
				(type solid)
			)
			(layer "B.Fab")
		)
		(fp_circle
			(center -0.9652 -0.9652)
			(end -0.9144 -0.9652)
			(stroke
				(width 0.15)
				(type solid)
			)
			(fill no)
			(layer "B.Fab")
		)
		(pad "1" smd rect
			(at -0.5 -0.65)
			(size 0.4 0.51)
			(layers "B.Cu" "B.Mask" "B.Paste")
			(net 10 "/Power/OUT_1V8")
			(pinfunction "G")
			(pintype "input")
		)
		(pad "2" smd rect
			(at 0.498 -0.65)
			(size 0.4 0.51)
			(layers "B.Cu" "B.Mask" "B.Paste")
			(net 1 "GND")
			(pinfunction "S")
			(pintype "passive")
		)
		(pad "3" smd rect
			(at 0 0.652)
			(size 0.4 0.51)
			(layers "B.Cu" "B.Mask" "B.Paste")
			(net 145 "Net-(D20-C)")
			(pinfunction "D")
			(pintype "passive")
		)
	)
)
